(kicad_pcb
	(version 20260206)
	(generator "pcbnew")
	(generator_version "10.0")
	(general
		(thickness 1.6)
		(legacy_teardrops no)
	)
	(paper "A4")
	(title_block
		(title "03242023_DA0F0TMBIJ0_F0T_Motherboard_J_brd_V01_OCP.brd")
		(comment 1 "Grand Teton / footprints 188-193 of 6105")
	)
	(layers
		(0 "F.Cu" signal "TOP")
		(4 "In1.Cu" signal "GND")
		(6 "In2.Cu" signal "IN1")
		(8 "In3.Cu" signal "GND1")
		(10 "In4.Cu" signal "IN2")
		(12 "In5.Cu" signal "GND2")
		(14 "In6.Cu" signal "IN3")
		(16 "In7.Cu" signal "GND3")
		(18 "In8.Cu" signal "VCC")
		(20 "In9.Cu" signal "VCC1")
		(22 "In10.Cu" signal "GND4")
		(24 "In11.Cu" signal "IN4")
		(26 "In12.Cu" signal "GND5")
		(28 "In13.Cu" signal "IN5")
		(30 "In14.Cu" signal "GND6")
		(32 "In15.Cu" signal "IN6")
		(34 "In16.Cu" signal "GND7")
		(2 "B.Cu" signal "BOTTOM")
		(9 "F.Adhes" user "F.Adhesive")
		(11 "B.Adhes" user "B.Adhesive")
		(13 "F.Paste" user "Package Geometry/Pastemask Top")
		(15 "B.Paste" user "Package Geometry/Pastemask Bottom")
		(5 "F.SilkS" user "Ref Des/Silkscreen Top")
		(7 "B.SilkS" user "Ref Des/Silkscreen Bottom")
		(1 "F.Mask" user "Board Geometry/Soldermask Top")
		(3 "B.Mask" user "Board Geometry/Soldermask Bottom")
		(17 "Dwgs.User" user "User.Drawings")
		(19 "Cmts.User" user "User.Comments")
		(21 "Eco1.User" user "User.Eco1")
		(23 "Eco2.User" user "User.Eco2")
		(25 "Edge.Cuts" user "Board Geometry/Outline")
		(27 "Margin" user)
		(31 "F.CrtYd" user "Package Geometry/Place Bound Top")
		(29 "B.CrtYd" user "Package Geometry/Place Bound Bottom")
		(35 "F.Fab" user "Ref Des/Assembly Top")
		(33 "B.Fab" user "Ref Des/Assembly Bottom")
	)
	(footprint ""
		(layer "F.Cu")
		(at 306.516024 -438.120536 -90)
		(property "Reference" "R4139"
			(at 0 0 270)
			(layer "F.SilkS")
			(hide yes)
			(effects
				(font
					(size 1.27 1.27)
				)
			)
		)
		(property "Value" ""
			(at 0 0 270)
			(layer "F.Fab")
			(effects
				(font
					(size 1.27 1.27)
				)
			)
		)
		(duplicate_pad_numbers_are_jumpers no)
		(fp_line
			(start -0.7874 0.4064)
			(end -0.7874 -0.4064)
			(stroke
				(width 0.1524)
				(type default)
			)
			(layer "F.SilkS")
		)
		(fp_line
			(start 0.7874 0.4064)
			(end -0.7874 0.4064)
			(stroke
				(width 0.1524)
				(type default)
			)
			(layer "F.SilkS")
		)
		(fp_line
			(start -0.7874 -0.4064)
			(end 0.7874 -0.4064)
			(stroke
				(width 0.1524)
				(type default)
			)
			(layer "F.SilkS")
		)
		(fp_line
			(start 0.7874 -0.4064)
			(end 0.7874 0.4064)
			(stroke
				(width 0.1524)
				(type default)
			)
			(layer "F.SilkS")
		)
		(fp_line
			(start -0.67945 0.3048)
			(end -0.67945 -0.305054)
			(stroke
				(width 0.1)
				(type default)
			)
			(layer "F.Fab")
		)
		(fp_line
			(start -0.12065 0.3048)
			(end -0.67945 0.3048)
			(stroke
				(width 0.1)
				(type default)
			)
			(layer "F.Fab")
		)
		(fp_line
			(start 0.120396 0.3048)
			(end 0.120396 0.2794)
			(stroke
				(width 0.1)
				(type default)
			)
			(layer "F.Fab")
		)
		(fp_line
			(start 0.67945 0.3048)
			(end 0.120396 0.3048)
			(stroke
				(width 0.1)
				(type default)
			)
			(layer "F.Fab")
		)
		(fp_line
			(start -0.12065 0.2794)
			(end -0.12065 0.3048)
			(stroke
				(width 0.1)
				(type default)
			)
			(layer "F.Fab")
		)
		(fp_line
			(start 0.120396 0.2794)
			(end -0.12065 0.2794)
			(stroke
				(width 0.1)
				(type default)
			)
			(layer "F.Fab")
		)
		(fp_line
			(start -0.12065 -0.2794)
			(end 0.12065 -0.2794)
			(stroke
				(width 0.1)
				(type default)
			)
			(layer "F.Fab")
		)
		(fp_line
			(start 0.12065 -0.2794)
			(end 0.12065 -0.3048)
			(stroke
				(width 0.1)
				(type default)
			)
			(layer "F.Fab")
		)
		(fp_line
			(start 0.12065 -0.3048)
			(end 0.67945 -0.3048)
			(stroke
				(width 0.1)
				(type default)
			)
			(layer "F.Fab")
		)
		(fp_line
			(start 0.67945 -0.3048)
			(end 0.67945 0.3048)
			(stroke
				(width 0.1)
				(type default)
			)
			(layer "F.Fab")
		)
		(fp_line
			(start -0.67945 -0.305054)
			(end -0.12065 -0.305054)
			(stroke
				(width 0.1)
				(type default)
			)
			(layer "F.Fab")
		)
		(fp_line
			(start -0.12065 -0.305054)
			(end -0.12065 -0.2794)
			(stroke
				(width 0.1)
				(type default)
			)
			(layer "F.Fab")
		)
		(pad "1" smd circle
			(at -0.40005 0 270)
			(size 0 0)
			(layers "F.Cu" "F.Mask" "F.Paste")
			(net "P3V3_AUX")
		)
		(pad "2" smd circle
			(at 0.40005 0 270)
			(size 0 0)
			(layers "F.Cu" "F.Mask" "F.Paste")
			(net "PRSNT_CABLE_GPU_A2")
		)
	)
	(footprint ""
		(layer "F.Cu")
		(at 170.23588 -439.003948 180)
		(property "Reference" "R3453"
			(at 0 0 180)
			(layer "F.SilkS")
			(hide yes)
			(effects
				(font
					(size 1.27 1.27)
				)
			)
		)
		(property "Value" ""
			(at 0 0 180)
			(layer "F.Fab")
			(effects
				(font
					(size 1.27 1.27)
				)
			)
		)
		(duplicate_pad_numbers_are_jumpers no)
		(fp_line
			(start 0.7874 0.4064)
			(end -0.7874 0.4064)
			(stroke
				(width 0.1524)
				(type default)
			)
			(layer "F.SilkS")
		)
		(fp_line
			(start 0.7874 -0.4064)
			(end 0.7874 0.4064)
			(stroke
				(width 0.1524)
				(type default)
			)
			(layer "F.SilkS")
		)
		(fp_line
			(start -0.7874 0.4064)
			(end -0.7874 -0.4064)
			(stroke
				(width 0.1524)
				(type default)
			)
			(layer "F.SilkS")
		)
		(fp_line
			(start -0.7874 -0.4064)
			(end 0.7874 -0.4064)
			(stroke
				(width 0.1524)
				(type default)
			)
			(layer "F.SilkS")
		)
		(fp_line
			(start 0.67945 0.3048)
			(end 0.120396 0.3048)
			(stroke
				(width 0.1)
				(type default)
			)
			(layer "F.Fab")
		)
		(fp_line
			(start 0.67945 -0.3048)
			(end 0.67945 0.3048)
			(stroke
				(width 0.1)
				(type default)
			)
			(layer "F.Fab")
		)
		(fp_line
			(start 0.12065 -0.2794)
			(end 0.12065 -0.3048)
			(stroke
				(width 0.1)
				(type default)
			)
			(layer "F.Fab")
		)
		(fp_line
			(start 0.12065 -0.3048)
			(end 0.67945 -0.3048)
			(stroke
				(width 0.1)
				(type default)
			)
			(layer "F.Fab")
		)
		(fp_line
			(start 0.120396 0.3048)
			(end 0.120396 0.2794)
			(stroke
				(width 0.1)
				(type default)
			)
			(layer "F.Fab")
		)
		(fp_line
			(start 0.120396 0.2794)
			(end -0.12065 0.2794)
			(stroke
				(width 0.1)
				(type default)
			)
			(layer "F.Fab")
		)
		(fp_line
			(start -0.12065 0.3048)
			(end -0.67945 0.3048)
			(stroke
				(width 0.1)
				(type default)
			)
			(layer "F.Fab")
		)
		(fp_line
			(start -0.12065 0.2794)
			(end -0.12065 0.3048)
			(stroke
				(width 0.1)
				(type default)
			)
			(layer "F.Fab")
		)
		(fp_line
			(start -0.12065 -0.2794)
			(end 0.12065 -0.2794)
			(stroke
				(width 0.1)
				(type default)
			)
			(layer "F.Fab")
		)
		(fp_line
			(start -0.12065 -0.305054)
			(end -0.12065 -0.2794)
			(stroke
				(width 0.1)
				(type default)
			)
			(layer "F.Fab")
		)
		(fp_line
			(start -0.67945 0.3048)
			(end -0.67945 -0.305054)
			(stroke
				(width 0.1)
				(type default)
			)
			(layer "F.Fab")
		)
		(fp_line
			(start -0.67945 -0.305054)
			(end -0.12065 -0.305054)
			(stroke
				(width 0.1)
				(type default)
			)
			(layer "F.Fab")
		)
		(pad "1" smd circle
			(at -0.40005 0 180)
			(size 0 0)
			(layers "F.Cu" "F.Mask" "F.Paste")
			(net "P3V3_AUX")
		)
		(pad "2" smd circle
			(at 0.40005 0 180)
			(size 0 0)
			(layers "F.Cu" "F.Mask" "F.Paste")
			(net "GPU_FPGA_BOOT_EN_BUF_R")
		)
	)
	(footprint ""
		(layer "F.Cu")
		(at 182.17388 -130.266948 -90)
		(property "Reference" "R284"
			(at 0 0 270)
			(layer "F.SilkS")
			(hide yes)
			(effects
				(font
					(size 1.27 1.27)
				)
			)
		)
		(property "Value" ""
			(at 0 0 270)
			(layer "F.Fab")
			(effects
				(font
					(size 1.27 1.27)
				)
			)
		)
		(duplicate_pad_numbers_are_jumpers no)
		(fp_line
			(start -0.7874 0.4064)
			(end -0.7874 -0.4064)
			(stroke
				(width 0.1524)
				(type default)
			)
			(layer "F.SilkS")
		)
		(fp_line
			(start 0.7874 0.4064)
			(end -0.7874 0.4064)
			(stroke
				(width 0.1524)
				(type default)
			)
			(layer "F.SilkS")
		)
		(fp_line
			(start -0.7874 -0.4064)
			(end 0.7874 -0.4064)
			(stroke
				(width 0.1524)
				(type default)
			)
			(layer "F.SilkS")
		)
		(fp_line
			(start 0.7874 -0.4064)
			(end 0.7874 0.4064)
			(stroke
				(width 0.1524)
				(type default)
			)
			(layer "F.SilkS")
		)
		(fp_line
			(start -0.67945 0.3048)
			(end -0.67945 -0.305054)
			(stroke
				(width 0.1)
				(type default)
			)
			(layer "F.Fab")
		)
		(fp_line
			(start -0.12065 0.3048)
			(end -0.67945 0.3048)
			(stroke
				(width 0.1)
				(type default)
			)
			(layer "F.Fab")
		)
		(fp_line
			(start 0.120396 0.3048)
			(end 0.120396 0.2794)
			(stroke
				(width 0.1)
				(type default)
			)
			(layer "F.Fab")
		)
		(fp_line
			(start 0.67945 0.3048)
			(end 0.120396 0.3048)
			(stroke
				(width 0.1)
				(type default)
			)
			(layer "F.Fab")
		)
		(fp_line
			(start -0.12065 0.2794)
			(end -0.12065 0.3048)
			(stroke
				(width 0.1)
				(type default)
			)
			(layer "F.Fab")
		)
		(fp_line
			(start 0.120396 0.2794)
			(end -0.12065 0.2794)
			(stroke
				(width 0.1)
				(type default)
			)
			(layer "F.Fab")
		)
		(fp_line
			(start -0.12065 -0.2794)
			(end 0.12065 -0.2794)
			(stroke
				(width 0.1)
				(type default)
			)
			(layer "F.Fab")
		)
		(fp_line
			(start 0.12065 -0.2794)
			(end 0.12065 -0.3048)
			(stroke
				(width 0.1)
				(type default)
			)
			(layer "F.Fab")
		)
		(fp_line
			(start 0.12065 -0.3048)
			(end 0.67945 -0.3048)
			(stroke
				(width 0.1)
				(type default)
			)
			(layer "F.Fab")
		)
		(fp_line
			(start 0.67945 -0.3048)
			(end 0.67945 0.3048)
			(stroke
				(width 0.1)
				(type default)
			)
			(layer "F.Fab")
		)
		(fp_line
			(start -0.67945 -0.305054)
			(end -0.12065 -0.305054)
			(stroke
				(width 0.1)
				(type default)
			)
			(layer "F.Fab")
		)
		(fp_line
			(start -0.12065 -0.305054)
			(end -0.12065 -0.2794)
			(stroke
				(width 0.1)
				(type default)
			)
			(layer "F.Fab")
		)
		(pad "1" smd circle
			(at -0.40005 0 270)
			(size 0 0)
			(layers "F.Cu" "F.Mask" "F.Paste")
			(net "P3V3_AUX")
		)
		(pad "2" smd circle
			(at 0.40005 0 270)
			(size 0 0)
			(layers "F.Cu" "F.Mask" "F.Paste")
			(net "FM_CPU0_PKGID1")
		)
	)
	(footprint ""
		(layer "F.Cu")
		(at 91.754198 -402.371052 -90)
		(property "Reference" "C739"
			(at 0 0 270)
			(layer "F.SilkS")
			(hide yes)
			(effects
				(font
					(size 1.27 1.27)
				)
			)
		)
		(property "Value" ""
			(at 0 0 270)
			(layer "F.Fab")
			(effects
				(font
					(size 1.27 1.27)
				)
			)
		)
		(duplicate_pad_numbers_are_jumpers no)
		(fp_line
			(start -0.299974 0.150114)
			(end -0.299974 -0.150114)
			(stroke
				(width 0.1)
				(type default)
			)
			(layer "F.Fab")
		)
		(fp_line
			(start 0.299974 0.150114)
			(end -0.299974 0.150114)
			(stroke
				(width 0.1)
				(type default)
			)
			(layer "F.Fab")
		)
		(fp_line
			(start -0.299974 -0.150114)
			(end 0.299974 -0.150114)
			(stroke
				(width 0.1)
				(type default)
			)
			(layer "F.Fab")
		)
		(fp_line
			(start 0.299974 -0.150114)
			(end 0.299974 0.150114)
			(stroke
				(width 0.1)
				(type default)
			)
			(layer "F.Fab")
		)
		(pad "1" smd rect
			(at -0.2667 0 270)
			(size 0.3048 0.381)
			(layers "F.Cu" "F.Mask" "F.Paste")
			(net "P5E_CPU1_PE0_TX_C_DP<1>")
		)
		(pad "2" smd rect
			(at 0.2667 0 270)
			(size 0.3048 0.381)
			(layers "F.Cu" "F.Mask" "F.Paste")
			(net "P5E_CPU1_PE0_TX_DP<1>")
		)
	)
	(footprint ""
		(layer "F.Cu")
		(at 122.35688 -99.405948)
		(property "Reference" "R4397"
			(at 0 0 0)
			(layer "F.SilkS")
			(hide yes)
			(effects
				(font
					(size 1.27 1.27)
				)
			)
		)
		(property "Value" ""
			(at 0 0 0)
			(layer "F.Fab")
			(effects
				(font
					(size 1.27 1.27)
				)
			)
		)
		(duplicate_pad_numbers_are_jumpers no)
		(fp_line
			(start -0.7874 -0.4064)
			(end 0.7874 -0.4064)
			(stroke
				(width 0.1524)
				(type default)
			)
			(layer "F.SilkS")
		)
		(fp_line
			(start -0.7874 0.4064)
			(end -0.7874 -0.4064)
			(stroke
				(width 0.1524)
				(type default)
			)
			(layer "F.SilkS")
		)
		(fp_line
			(start 0.7874 -0.4064)
			(end 0.7874 0.4064)
			(stroke
				(width 0.1524)
				(type default)
			)
			(layer "F.SilkS")
		)
		(fp_line
			(start 0.7874 0.4064)
			(end -0.7874 0.4064)
			(stroke
				(width 0.1524)
				(type default)
			)
			(layer "F.SilkS")
		)
		(fp_line
			(start -0.67945 -0.305054)
			(end -0.12065 -0.305054)
			(stroke
				(width 0.1)
				(type default)
			)
			(layer "F.Fab")
		)
		(fp_line
			(start -0.67945 0.3048)
			(end -0.67945 -0.305054)
			(stroke
				(width 0.1)
				(type default)
			)
			(layer "F.Fab")
		)
		(fp_line
			(start -0.12065 -0.305054)
			(end -0.12065 -0.2794)
			(stroke
				(width 0.1)
				(type default)
			)
			(layer "F.Fab")
		)
		(fp_line
			(start -0.12065 -0.2794)
			(end 0.12065 -0.2794)
			(stroke
				(width 0.1)
				(type default)
			)
			(layer "F.Fab")
		)
		(fp_line
			(start -0.12065 0.2794)
			(end -0.12065 0.3048)
			(stroke
				(width 0.1)
				(type default)
			)
			(layer "F.Fab")
		)
		(fp_line
			(start -0.12065 0.3048)
			(end -0.67945 0.3048)
			(stroke
				(width 0.1)
				(type default)
			)
			(layer "F.Fab")
		)
		(fp_line
			(start 0.120396 0.2794)
			(end -0.12065 0.2794)
			(stroke
				(width 0.1)
				(type default)
			)
			(layer "F.Fab")
		)
		(fp_line
			(start 0.120396 0.3048)
			(end 0.120396 0.2794)
			(stroke
				(width 0.1)
				(type default)
			)
			(layer "F.Fab")
		)
		(fp_line
			(start 0.12065 -0.3048)
			(end 0.67945 -0.3048)
			(stroke
				(width 0.1)
				(type default)
			)
			(layer "F.Fab")
		)
		(fp_line
			(start 0.12065 -0.2794)
			(end 0.12065 -0.3048)
			(stroke
				(width 0.1)
				(type default)
			)
			(layer "F.Fab")
		)
		(fp_line
			(start 0.67945 -0.3048)
			(end 0.67945 0.3048)
			(stroke
				(width 0.1)
				(type default)
			)
			(layer "F.Fab")
		)
		(fp_line
			(start 0.67945 0.3048)
			(end 0.120396 0.3048)
			(stroke
				(width 0.1)
				(type default)
			)
			(layer "F.Fab")
		)
		(pad "1" smd circle
			(at -0.40005 0)
			(size 0 0)
			(layers "F.Cu" "F.Mask" "F.Paste")
			(net "H_CPU0_THERMTRIP_N")
		)
		(pad "2" smd circle
			(at 0.40005 0)
			(size 0 0)
			(layers "F.Cu" "F.Mask" "F.Paste")
			(net "H_CPU0_THERMTRIP_R_N")
		)
	)
	(footprint ""
		(layer "F.Cu")
		(at 335.754726 -16.200628 -90)
		(property "Reference" "R1215"
			(at 0 0 270)
			(layer "F.SilkS")
			(hide yes)
			(effects
				(font
					(size 1.27 1.27)
				)
			)
		)
		(property "Value" ""
			(at 0 0 270)
			(layer "F.Fab")
			(effects
				(font
					(size 1.27 1.27)
				)
			)
		)
		(duplicate_pad_numbers_are_jumpers no)
		(fp_line
			(start -0.7874 0.4064)
			(end -0.7874 -0.4064)
			(stroke
				(width 0.1524)
				(type default)
			)
			(layer "F.SilkS")
		)
		(fp_line
			(start 0.7874 0.4064)
			(end -0.7874 0.4064)
			(stroke
				(width 0.1524)
				(type default)
			)
			(layer "F.SilkS")
		)
		(fp_line
			(start -0.7874 -0.4064)
			(end 0.7874 -0.4064)
			(stroke
				(width 0.1524)
				(type default)
			)
			(layer "F.SilkS")
		)
		(fp_line
			(start 0.7874 -0.4064)
			(end 0.7874 0.4064)
			(stroke
				(width 0.1524)
				(type default)
			)
			(layer "F.SilkS")
		)
		(fp_line
			(start -0.67945 0.3048)
			(end -0.67945 -0.305054)
			(stroke
				(width 0.1)
				(type default)
			)
			(layer "F.Fab")
		)
		(fp_line
			(start -0.12065 0.3048)
			(end -0.67945 0.3048)
			(stroke
				(width 0.1)
				(type default)
			)
			(layer "F.Fab")
		)
		(fp_line
			(start 0.120396 0.3048)
			(end 0.120396 0.2794)
			(stroke
				(width 0.1)
				(type default)
			)
			(layer "F.Fab")
		)
		(fp_line
			(start 0.67945 0.3048)
			(end 0.120396 0.3048)
			(stroke
				(width 0.1)
				(type default)
			)
			(layer "F.Fab")
		)
		(fp_line
			(start -0.12065 0.2794)
			(end -0.12065 0.3048)
			(stroke
				(width 0.1)
				(type default)
			)
			(layer "F.Fab")
		)
		(fp_line
			(start 0.120396 0.2794)
			(end -0.12065 0.2794)
			(stroke
				(width 0.1)
				(type default)
			)
			(layer "F.Fab")
		)
		(fp_line
			(start -0.12065 -0.2794)
			(end 0.12065 -0.2794)
			(stroke
				(width 0.1)
				(type default)
			)
			(layer "F.Fab")
		)
		(fp_line
			(start 0.12065 -0.2794)
			(end 0.12065 -0.3048)
			(stroke
				(width 0.1)
				(type default)
			)
			(layer "F.Fab")
		)
		(fp_line
			(start 0.12065 -0.3048)
			(end 0.67945 -0.3048)
			(stroke
				(width 0.1)
				(type default)
			)
			(layer "F.Fab")
		)
		(fp_line
			(start 0.67945 -0.3048)
			(end 0.67945 0.3048)
			(stroke
				(width 0.1)
				(type default)
			)
			(layer "F.Fab")
		)
		(fp_line
			(start -0.67945 -0.305054)
			(end -0.12065 -0.305054)
			(stroke
				(width 0.1)
				(type default)
			)
			(layer "F.Fab")
		)
		(fp_line
			(start -0.12065 -0.305054)
			(end -0.12065 -0.2794)
			(stroke
				(width 0.1)
				(type default)
			)
			(layer "F.Fab")
		)
		(pad "1" smd circle
			(at -0.40005 0 270)
			(size 0 0)
			(layers "F.Cu" "F.Mask" "F.Paste")
			(net "IRQ_ESPI_LPC_SERIRQ_ALERT_N")
		)
		(pad "2" smd circle
			(at 0.40005 0 270)
			(size 0 0)
			(layers "F.Cu" "F.Mask" "F.Paste")
			(net "IRQ_ESPI_LPC_SERIRQ_ALERT_R_N")
		)
	)
)
